# T6G (Grand Teton) — schematic netlist excerpt (pin names and nets, part order shuffled) for the footprints in the layout excerpt that follows; sources: Cadence DE-HDL packaged netlist, KiCad conversion of 04192023_DAF0TMB3IC0_F0TG_MB_C_brd_V02_OCP.brd

R4184  Q_RES  1K 1% EMPTY  pkg 0402LF  page 235 : A = P3V3_AUX ; B = U273_3_ADD2
R6741  Q_RES  0 5% CHIP  pkg 0402LF  page 81 : A = RST_RT_CPU1_P1_RESET_R_N ; B = RST_RT_CPU1_P1_RESET_R2_N
PL12  Q_INDUCTOR  50NH/86A IND  pkg SMLF  page 201 : \1\ = SW_P12V_AUX_PVDDCR_CPU1_P0_FLT ; \2\ = P12V_AUX

(kicad_pcb
	(version 20260206)
	(generator "pcbnew")
	(generator_version "10.0")
	(general
		(thickness 1.6)
		(legacy_teardrops no)
	)
	(paper "A4")
	(title_block
		(title "04192023_DAF0TMB3IC0_F0TG_MB_C_brd_V02_OCP.brd")
		(comment 1 "Grand Teton / footprints 1697-1699 of 8354")
	)
	(layers
		(0 "F.Cu" signal "TOP")
		(4 "In1.Cu" signal "GND")
		(6 "In2.Cu" signal "IN1")
		(8 "In3.Cu" signal "GND1")
		(10 "In4.Cu" signal "IN2")
		(12 "In5.Cu" signal "GND2")
		(14 "In6.Cu" signal "IN3")
		(16 "In7.Cu" signal "GND3")
		(18 "In8.Cu" signal "VCC")
		(20 "In9.Cu" signal "VCC1")
		(22 "In10.Cu" signal "GND4")
		(24 "In11.Cu" signal "IN4")
		(26 "In12.Cu" signal "GND5")
		(28 "In13.Cu" signal "IN5")
		(30 "In14.Cu" signal "GND6")
		(32 "In15.Cu" signal "IN6")
		(34 "In16.Cu" signal "GND7")
		(2 "B.Cu" signal "BOTTOM")
		(9 "F.Adhes" user "F.Adhesive")
		(11 "B.Adhes" user "B.Adhesive")
		(13 "F.Paste" user "Package Geometry/Pastemask Top")
		(15 "B.Paste" user "Package Geometry/Pastemask Bottom")
		(5 "F.SilkS" user "Ref Des/Silkscreen Top")
		(7 "B.SilkS" user "Ref Des/Silkscreen Bottom")
		(1 "F.Mask" user "Board Geometry/Soldermask Top")
		(3 "B.Mask" user "Board Geometry/Soldermask Bottom")
		(17 "Dwgs.User" user "User.Drawings")
		(19 "Cmts.User" user "User.Comments")
		(21 "Eco1.User" user "User.Eco1")
		(23 "Eco2.User" user "User.Eco2")
		(25 "Edge.Cuts" user "Board Geometry/Outline")
		(27 "Margin" user)
		(31 "F.CrtYd" user "Package Geometry/Place Bound Top")
		(29 "B.CrtYd" user "Package Geometry/Place Bound Bottom")
		(35 "F.Fab" user "Ref Des/Assembly Top")
		(33 "B.Fab" user "Ref Des/Assembly Bottom")
	)
	(footprint ""
		(layer "F.Cu")
		(at 341.648542 -356.05339 90)
		(property "Reference" "PL12"
			(at -1.4224 3.870452 90)
			(unlocked yes)
			(layer "F.SilkS")
			(effects
				(font
					(size 0.7874 0.5842)
					(thickness 0.1524)
				)
				(justify left)
			)
		)
		(property "Value" ""
			(at 0 0 90)
			(layer "F.Fab")
			(effects
				(font
					(size 1.27 1.27)
				)
			)
		)
		(duplicate_pad_numbers_are_jumpers no)
		(fp_line
			(start 3.050032 -2.999994)
			(end -3.050032 -2.999994)
			(stroke
				(width 0.1524)
				(type default)
			)
			(layer "F.SilkS")
		)
		(fp_line
			(start -3.050032 -2.999994)
			(end -3.050032 -1.4478)
			(stroke
				(width 0.1524)
				(type default)
			)
			(layer "F.SilkS")
		)
		(fp_line
			(start 3.050032 -1.4478)
			(end 3.050032 -2.999994)
			(stroke
				(width 0.1524)
				(type default)
			)
			(layer "F.SilkS")
		)
		(fp_line
			(start -3.050032 1.4478)
			(end -3.050032 2.999994)
			(stroke
				(width 0.1524)
				(type default)
			)
			(layer "F.SilkS")
		)
		(fp_line
			(start 3.050032 2.999994)
			(end 3.050032 1.4478)
			(stroke
				(width 0.1524)
				(type default)
			)
			(layer "F.SilkS")
		)
		(fp_line
			(start -3.050032 2.999994)
			(end 3.050032 2.999994)
			(stroke
				(width 0.1524)
				(type default)
			)
			(layer "F.SilkS")
		)
		(fp_line
			(start 3.050032 -2.999994)
			(end -3.050032 -2.999994)
			(stroke
				(width 0.1)
				(type default)
			)
			(layer "F.Fab")
		)
		(fp_line
			(start -3.050032 -2.999994)
			(end -3.050032 2.999994)
			(stroke
				(width 0.1)
				(type default)
			)
			(layer "F.Fab")
		)
		(fp_line
			(start 3.050032 2.999994)
			(end 3.050032 -2.999994)
			(stroke
				(width 0.1)
				(type default)
			)
			(layer "F.Fab")
		)
		(fp_line
			(start -3.050032 2.999994)
			(end 3.050032 2.999994)
			(stroke
				(width 0.1)
				(type default)
			)
			(layer "F.Fab")
		)
		(pad "1" smd rect
			(at -2.525014 0 90)
			(size 1.651 2.6162)
			(layers "F.Cu" "F.Mask" "F.Paste")
			(net "SW_P12V_AUX_PVDDCR_CPU1_P0_FLT")
		)
		(pad "2" smd rect
			(at 2.525014 0 90)
			(size 1.651 2.6162)
			(layers "F.Cu" "F.Mask" "F.Paste")
			(net "P12V_AUX")
		)
	)
	(footprint ""
		(layer "F.Cu")
		(at 179.961286 -133.43763 -90)
		(property "Reference" "R6741"
			(at 0 0 270)
			(layer "F.SilkS")
			(hide yes)
			(effects
				(font
					(size 1.27 1.27)
				)
			)
		)
		(property "Value" ""
			(at 0 0 270)
			(layer "F.Fab")
			(effects
				(font
					(size 1.27 1.27)
				)
			)
		)
		(duplicate_pad_numbers_are_jumpers no)
		(fp_line
			(start -0.7874 0.4064)
			(end -0.7874 -0.4064)
			(stroke
				(width 0.1524)
				(type default)
			)
			(layer "F.SilkS")
		)
		(fp_line
			(start 0.7874 0.4064)
			(end -0.7874 0.4064)
			(stroke
				(width 0.1524)
				(type default)
			)
			(layer "F.SilkS")
		)
		(fp_line
			(start -0.7874 -0.4064)
			(end 0.7874 -0.4064)
			(stroke
				(width 0.1524)
				(type default)
			)
			(layer "F.SilkS")
		)
		(fp_line
			(start 0.7874 -0.4064)
			(end 0.7874 0.4064)
			(stroke
				(width 0.1524)
				(type default)
			)
			(layer "F.SilkS")
		)
		(fp_line
			(start -0.67945 0.3048)
			(end -0.67945 -0.305054)
			(stroke
				(width 0.1)
				(type default)
			)
			(layer "F.Fab")
		)
		(fp_line
			(start -0.12065 0.3048)
			(end -0.67945 0.3048)
			(stroke
				(width 0.1)
				(type default)
			)
			(layer "F.Fab")
		)
		(fp_line
			(start 0.120396 0.3048)
			(end 0.120396 0.2794)
			(stroke
				(width 0.1)
				(type default)
			)
			(layer "F.Fab")
		)
		(fp_line
			(start 0.67945 0.3048)
			(end 0.120396 0.3048)
			(stroke
				(width 0.1)
				(type default)
			)
			(layer "F.Fab")
		)
		(fp_line
			(start -0.12065 0.2794)
			(end -0.12065 0.3048)
			(stroke
				(width 0.1)
				(type default)
			)
			(layer "F.Fab")
		)
		(fp_line
			(start 0.120396 0.2794)
			(end -0.12065 0.2794)
			(stroke
				(width 0.1)
				(type default)
			)
			(layer "F.Fab")
		)
		(fp_line
			(start -0.12065 -0.2794)
			(end 0.12065 -0.2794)
			(stroke
				(width 0.1)
				(type default)
			)
			(layer "F.Fab")
		)
		(fp_line
			(start 0.12065 -0.2794)
			(end 0.12065 -0.3048)
			(stroke
				(width 0.1)
				(type default)
			)
			(layer "F.Fab")
		)
		(fp_line
			(start 0.12065 -0.3048)
			(end 0.67945 -0.3048)
			(stroke
				(width 0.1)
				(type default)
			)
			(layer "F.Fab")
		)
		(fp_line
			(start 0.67945 -0.3048)
			(end 0.67945 0.3048)
			(stroke
				(width 0.1)
				(type default)
			)
			(layer "F.Fab")
		)
		(fp_line
			(start -0.67945 -0.305054)
			(end -0.12065 -0.305054)
			(stroke
				(width 0.1)
				(type default)
			)
			(layer "F.Fab")
		)
		(fp_line
			(start -0.12065 -0.305054)
			(end -0.12065 -0.2794)
			(stroke
				(width 0.1)
				(type default)
			)
			(layer "F.Fab")
		)
		(pad "1" smd circle
			(at -0.40005 0 270)
			(size 0 0)
			(layers "F.Cu" "F.Mask" "F.Paste")
			(net "RST_RT_CPU1_P1_RESET_R_N")
		)
		(pad "2" smd circle
			(at 0.40005 0 270)
			(size 0 0)
			(layers "F.Cu" "F.Mask" "F.Paste")
			(net "RST_RT_CPU1_P1_RESET_R2_N")
		)
	)
	(footprint ""
		(layer "F.Cu")
		(at 123.835922 -13.99413 180)
		(property "Reference" "R4184"
			(at 0 0 180)
			(layer "F.SilkS")
			(hide yes)
			(effects
				(font
					(size 1.27 1.27)
				)
			)
		)
		(property "Value" ""
			(at 0 0 180)
			(layer "F.Fab")
			(effects
				(font
					(size 1.27 1.27)
				)
			)
		)
		(duplicate_pad_numbers_are_jumpers no)
		(fp_line
			(start 0.7874 0.4064)
			(end -0.7874 0.4064)
			(stroke
				(width 0.1524)
				(type default)
			)
			(layer "F.SilkS")
		)
		(fp_line
			(start 0.7874 -0.4064)
			(end 0.7874 0.4064)
			(stroke
				(width 0.1524)
				(type default)
			)
			(layer "F.SilkS")
		)
		(fp_line
			(start -0.7874 0.4064)
			(end -0.7874 -0.4064)
			(stroke
				(width 0.1524)
				(type default)
			)
			(layer "F.SilkS")
		)
		(fp_line
			(start -0.7874 -0.4064)
			(end 0.7874 -0.4064)
			(stroke
				(width 0.1524)
				(type default)
			)
			(layer "F.SilkS")
		)
		(fp_line
			(start 0.67945 0.3048)
			(end 0.120396 0.3048)
			(stroke
				(width 0.1)
				(type default)
			)
			(layer "F.Fab")
		)
		(fp_line
			(start 0.67945 -0.3048)
			(end 0.67945 0.3048)
			(stroke
				(width 0.1)
				(type default)
			)
			(layer "F.Fab")
		)
		(fp_line
			(start 0.12065 -0.2794)
			(end 0.12065 -0.3048)
			(stroke
				(width 0.1)
				(type default)
			)
			(layer "F.Fab")
		)
		(fp_line
			(start 0.12065 -0.3048)
			(end 0.67945 -0.3048)
			(stroke
				(width 0.1)
				(type default)
			)
			(layer "F.Fab")
		)
		(fp_line
			(start 0.120396 0.3048)
			(end 0.120396 0.2794)
			(stroke
				(width 0.1)
				(type default)
			)
			(layer "F.Fab")
		)
		(fp_line
			(start 0.120396 0.2794)
			(end -0.12065 0.2794)
			(stroke
				(width 0.1)
				(type default)
			)
			(layer "F.Fab")
		)
		(fp_line
			(start -0.12065 0.3048)
			(end -0.67945 0.3048)
			(stroke
				(width 0.1)
				(type default)
			)
			(layer "F.Fab")
		)
		(fp_line
			(start -0.12065 0.2794)
			(end -0.12065 0.3048)
			(stroke
				(width 0.1)
				(type default)
			)
			(layer "F.Fab")
		)
		(fp_line
			(start -0.12065 -0.2794)
			(end 0.12065 -0.2794)
			(stroke
				(width 0.1)
				(type default)
			)
			(layer "F.Fab")
		)
		(fp_line
			(start -0.12065 -0.305054)
			(end -0.12065 -0.2794)
			(stroke
				(width 0.1)
				(type default)
			)
			(layer "F.Fab")
		)
		(fp_line
			(start -0.67945 0.3048)
			(end -0.67945 -0.305054)
			(stroke
				(width 0.1)
				(type default)
			)
			(layer "F.Fab")
		)
		(fp_line
			(start -0.67945 -0.305054)
			(end -0.12065 -0.305054)
			(stroke
				(width 0.1)
				(type default)
			)
			(layer "F.Fab")
		)
		(pad "1" smd circle
			(at -0.40005 0 180)
			(size 0 0)
			(layers "F.Cu" "F.Mask" "F.Paste")
			(net "P3V3_AUX")
		)
		(pad "2" smd circle
			(at 0.40005 0 180)
			(size 0 0)
			(layers "F.Cu" "F.Mask" "F.Paste")
			(net "U273_3_ADD2")
		)
	)
)
